# T6G (Grand Teton) — schematic netlist excerpt (pin names and nets, part order shuffled) for the footprints in the layout excerpt that follows; sources: Cadence DE-HDL packaged netlist, KiCad conversion of 04192023_DAF0TMB3IC0_F0TG_MB_C_brd_V02_OCP.brd

C7029  Q_CAPP  470UF 2.5V 20% SPCAP  pkg SMLF  page 356 : A = P0V9_CPU1_RT3_2A ; B = GND
C2358  Q_CAP  22UF 4V 20% X6S  pkg C0402  page 73 : A = PVDDCR_CPU1_P1 ; B = GND

(kicad_pcb
	(version 20260206)
	(generator "pcbnew")
	(generator_version "10.0")
	(general
		(thickness 1.6)
		(legacy_teardrops no)
	)
	(paper "A4")
	(title_block
		(title "04192023_DAF0TMB3IC0_F0TG_MB_C_brd_V02_OCP.brd")
		(comment 1 "Grand Teton / footprints 7839-7840 of 8354")
	)
	(layers
		(0 "F.Cu" signal "TOP")
		(4 "In1.Cu" signal "GND")
		(6 "In2.Cu" signal "IN1")
		(8 "In3.Cu" signal "GND1")
		(10 "In4.Cu" signal "IN2")
		(12 "In5.Cu" signal "GND2")
		(14 "In6.Cu" signal "IN3")
		(16 "In7.Cu" signal "GND3")
		(18 "In8.Cu" signal "VCC")
		(20 "In9.Cu" signal "VCC1")
		(22 "In10.Cu" signal "GND4")
		(24 "In11.Cu" signal "IN4")
		(26 "In12.Cu" signal "GND5")
		(28 "In13.Cu" signal "IN5")
		(30 "In14.Cu" signal "GND6")
		(32 "In15.Cu" signal "IN6")
		(34 "In16.Cu" signal "GND7")
		(2 "B.Cu" signal "BOTTOM")
		(9 "F.Adhes" user "F.Adhesive")
		(11 "B.Adhes" user "B.Adhesive")
		(13 "F.Paste" user "Package Geometry/Pastemask Top")
		(15 "B.Paste" user "Package Geometry/Pastemask Bottom")
		(5 "F.SilkS" user "Ref Des/Silkscreen Top")
		(7 "B.SilkS" user "Ref Des/Silkscreen Bottom")
		(1 "F.Mask" user "Board Geometry/Soldermask Top")
		(3 "B.Mask" user "Board Geometry/Soldermask Bottom")
		(17 "Dwgs.User" user "User.Drawings")
		(19 "Cmts.User" user "User.Comments")
		(21 "Eco1.User" user "User.Eco1")
		(23 "Eco2.User" user "User.Eco2")
		(25 "Edge.Cuts" user "Board Geometry/Outline")
		(27 "Margin" user)
		(31 "F.CrtYd" user "Package Geometry/Place Bound Top")
		(29 "B.CrtYd" user "Package Geometry/Place Bound Bottom")
		(35 "F.Fab" user "Ref Des/Assembly Top")
		(33 "B.Fab" user "Ref Des/Assembly Bottom")
	)
	(footprint ""
		(layer "B.Cu")
		(at 119.59717 -381.11303 180)
		(property "Reference" "C7029"
			(at -1.78308 -3.179572 0)
			(unlocked yes)
			(layer "B.SilkS")
			(effects
				(font
					(size 0.7874 0.5842)
					(thickness 0.1524)
				)
				(justify left mirror)
			)
		)
		(property "Value" ""
			(at 0 0 0)
			(layer "B.Fab")
			(effects
				(font
					(size 1.27 1.27)
				)
				(justify mirror)
			)
		)
		(duplicate_pad_numbers_are_jumpers no)
		(fp_line
			(start 4.84378 -2.150618)
			(end 4.842256 2.163064)
			(stroke
				(width 0.1524)
				(type default)
			)
			(layer "B.SilkS")
		)
		(fp_line
			(start 4.84378 -2.150618)
			(end 4.53898 -2.150618)
			(stroke
				(width 0.1524)
				(type default)
			)
			(layer "B.SilkS")
		)
		(fp_line
			(start 4.83108 2.150364)
			(end 4.447794 2.149348)
			(stroke
				(width 0.1524)
				(type default)
			)
			(layer "B.SilkS")
		)
		(fp_line
			(start 4.69138 -2.150618)
			(end 4.692396 2.161032)
			(stroke
				(width 0.1524)
				(type default)
			)
			(layer "B.SilkS")
		)
		(fp_line
			(start 4.53898 2.15011)
			(end 4.53898 -2.15011)
			(stroke
				(width 0.1524)
				(type default)
			)
			(layer "B.SilkS")
		)
		(fp_line
			(start 4.53898 -2.15011)
			(end -4.53898 -2.15011)
			(stroke
				(width 0.1524)
				(type default)
			)
			(layer "B.SilkS")
		)
		(fp_line
			(start 4.53898 -2.150618)
			(end 4.539742 2.152142)
			(stroke
				(width 0.1524)
				(type default)
			)
			(layer "B.SilkS")
		)
		(fp_line
			(start -4.53898 2.15011)
			(end 4.53898 2.15011)
			(stroke
				(width 0.1524)
				(type default)
			)
			(layer "B.SilkS")
		)
		(fp_line
			(start -4.53898 -2.15011)
			(end -4.53898 2.15011)
			(stroke
				(width 0.1524)
				(type default)
			)
			(layer "B.SilkS")
		)
		(fp_line
			(start 3.64998 2.15011)
			(end 3.64998 -2.15011)
			(stroke
				(width 0.1)
				(type default)
			)
			(layer "B.Fab")
		)
		(fp_line
			(start 3.64998 -2.15011)
			(end -3.64998 -2.15011)
			(stroke
				(width 0.1)
				(type default)
			)
			(layer "B.Fab")
		)
		(fp_line
			(start -3.64998 2.15011)
			(end 3.64998 2.15011)
			(stroke
				(width 0.1)
				(type default)
			)
			(layer "B.Fab")
		)
		(fp_line
			(start -3.64998 -2.15011)
			(end -3.64998 2.15011)
			(stroke
				(width 0.1)
				(type default)
			)
			(layer "B.Fab")
		)
		(fp_text user "+"
			(at 4.327652 -3.357118 180)
			(unlocked yes)
			(layer "B.SilkS")
			(effects
				(font
					(size 1.905 1.4224)
					(thickness 0.1524)
				)
				(justify left mirror)
			)
		)
		(fp_text user "-"
			(at -2.992374 -2.830068 180)
			(unlocked yes)
			(layer "B.SilkS")
			(effects
				(font
					(size 1.905 1.4224)
					(thickness 0.1524)
				)
				(justify left mirror)
			)
		)
		(fp_text user "+"
			(at 6.214872 -0.337058 180)
			(unlocked yes)
			(layer "B.Fab")
			(effects
				(font
					(size 1.905 1.4224)
					(thickness 0.1524)
				)
				(justify left mirror)
			)
		)
		(fp_text user "-"
			(at -4.313174 -0.094488 180)
			(unlocked yes)
			(layer "B.Fab")
			(effects
				(font
					(size 1.905 1.4224)
					(thickness 0.1524)
				)
				(justify left mirror)
			)
		)
		(pad "1" smd rect
			(at 3.199892 0)
			(size 2.413 2.8194)
			(layers "B.Cu" "B.Mask" "B.Paste")
			(net "P0V9_CPU1_RT3_2A")
		)
		(pad "2" smd rect
			(at -3.199892 0)
			(size 2.413 2.8194)
			(layers "B.Cu" "B.Mask" "B.Paste")
			(net "GND")
		)
	)
	(footprint ""
		(layer "B.Cu")
		(at 99.862386 -269.307564)
		(property "Reference" "C2358"
			(at 0 0 0)
			(layer "B.SilkS")
			(hide yes)
			(effects
				(font
					(size 1.27 1.27)
				)
				(justify mirror)
			)
		)
		(property "Value" ""
			(at 0 0 0)
			(layer "B.Fab")
			(effects
				(font
					(size 1.27 1.27)
				)
				(justify mirror)
			)
		)
		(duplicate_pad_numbers_are_jumpers no)
		(fp_line
			(start -0.7874 -0.4064)
			(end -0.7874 0.4064)
			(stroke
				(width 0.1524)
				(type default)
			)
			(layer "B.SilkS")
		)
		(fp_line
			(start -0.7874 0.4064)
			(end 0.7874 0.4064)
			(stroke
				(width 0.1524)
				(type default)
			)
			(layer "B.SilkS")
		)
		(fp_line
			(start 0.7874 -0.4064)
			(end -0.7874 -0.4064)
			(stroke
				(width 0.1524)
				(type default)
			)
			(layer "B.SilkS")
		)
		(fp_line
			(start 0.7874 0.4064)
			(end 0.7874 -0.4064)
			(stroke
				(width 0.1524)
				(type default)
			)
			(layer "B.SilkS")
		)
		(fp_line
			(start -0.67945 -0.3048)
			(end -0.67945 0.3048)
			(stroke
				(width 0.1)
				(type default)
			)
			(layer "B.Fab")
		)
		(fp_line
			(start -0.67945 0.3048)
			(end -0.120396 0.3048)
			(stroke
				(width 0.1)
				(type default)
			)
			(layer "B.Fab")
		)
		(fp_line
			(start -0.12065 -0.3048)
			(end -0.67945 -0.3048)
			(stroke
				(width 0.1)
				(type default)
			)
			(layer "B.Fab")
		)
		(fp_line
			(start -0.12065 -0.2794)
			(end -0.12065 -0.3048)
			(stroke
				(width 0.1)
				(type default)
			)
			(layer "B.Fab")
		)
		(fp_line
			(start -0.120396 0.2794)
			(end 0.12065 0.2794)
			(stroke
				(width 0.1)
				(type default)
			)
			(layer "B.Fab")
		)
		(fp_line
			(start -0.120396 0.3048)
			(end -0.120396 0.2794)
			(stroke
				(width 0.1)
				(type default)
			)
			(layer "B.Fab")
		)
		(fp_line
			(start 0.12065 -0.305054)
			(end 0.12065 -0.2794)
			(stroke
				(width 0.1)
				(type default)
			)
			(layer "B.Fab")
		)
		(fp_line
			(start 0.12065 -0.2794)
			(end -0.12065 -0.2794)
			(stroke
				(width 0.1)
				(type default)
			)
			(layer "B.Fab")
		)
		(fp_line
			(start 0.12065 0.2794)
			(end 0.12065 0.3048)
			(stroke
				(width 0.1)
				(type default)
			)
			(layer "B.Fab")
		)
		(fp_line
			(start 0.12065 0.3048)
			(end 0.67945 0.3048)
			(stroke
				(width 0.1)
				(type default)
			)
			(layer "B.Fab")
		)
		(fp_line
			(start 0.67945 -0.305054)
			(end 0.12065 -0.305054)
			(stroke
				(width 0.1)
				(type default)
			)
			(layer "B.Fab")
		)
		(fp_line
			(start 0.67945 0.3048)
			(end 0.67945 -0.305054)
			(stroke
				(width 0.1)
				(type default)
			)
			(layer "B.Fab")
		)
		(pad "1" smd circle
			(at 0.40005 0 180)
			(size 0 0)
			(layers "B.Cu" "B.Mask" "B.Paste")
			(net "PVDDCR_CPU1_P1")
		)
		(pad "2" smd circle
			(at -0.40005 0 180)
			(size 0 0)
			(layers "B.Cu" "B.Mask" "B.Paste")
			(net "GND")
		)
	)
)
